# S9S_MB_2U (Grand Teton) — schematic netlist excerpt (pin names and nets, part order shuffled) for the footprints in the layout excerpt that follows; sources: Cadence DE-HDL packaged netlist, KiCad conversion of 03242023_DA0F0TMBIJ0_F0T_Motherboard_J_brd_V01_OCP.brd

PC510  Q_CAP  100NF 50V 10% X7R  pkg C0402  page 287 : A = SW_PVCCIN_CPU1_BOOT5_R ; B = SW_PVCCIN_CPU1_BOOTR5
R1640  Q_RES  0 5% CHIP  pkg 0402LF  page 260 : A = FM_P5V_EN ; B = VR_P5V_EN

(kicad_pcb
	(version 20260206)
	(generator "pcbnew")
	(generator_version "10.0")
	(general
		(thickness 1.6)
		(legacy_teardrops no)
	)
	(paper "A4")
	(title_block
		(title "03242023_DA0F0TMBIJ0_F0T_Motherboard_J_brd_V01_OCP.brd")
		(comment 1 "Grand Teton / footprints 3579-3580 of 6105")
	)
	(layers
		(0 "F.Cu" signal "TOP")
		(4 "In1.Cu" signal "GND")
		(6 "In2.Cu" signal "IN1")
		(8 "In3.Cu" signal "GND1")
		(10 "In4.Cu" signal "IN2")
		(12 "In5.Cu" signal "GND2")
		(14 "In6.Cu" signal "IN3")
		(16 "In7.Cu" signal "GND3")
		(18 "In8.Cu" signal "VCC")
		(20 "In9.Cu" signal "VCC1")
		(22 "In10.Cu" signal "GND4")
		(24 "In11.Cu" signal "IN4")
		(26 "In12.Cu" signal "GND5")
		(28 "In13.Cu" signal "IN5")
		(30 "In14.Cu" signal "GND6")
		(32 "In15.Cu" signal "IN6")
		(34 "In16.Cu" signal "GND7")
		(2 "B.Cu" signal "BOTTOM")
		(9 "F.Adhes" user "F.Adhesive")
		(11 "B.Adhes" user "B.Adhesive")
		(13 "F.Paste" user "Package Geometry/Pastemask Top")
		(15 "B.Paste" user "Package Geometry/Pastemask Bottom")
		(5 "F.SilkS" user "Ref Des/Silkscreen Top")
		(7 "B.SilkS" user "Ref Des/Silkscreen Bottom")
		(1 "F.Mask" user "Board Geometry/Soldermask Top")
		(3 "B.Mask" user "Board Geometry/Soldermask Bottom")
		(17 "Dwgs.User" user "User.Drawings")
		(19 "Cmts.User" user "User.Comments")
		(21 "Eco1.User" user "User.Eco1")
		(23 "Eco2.User" user "User.Eco2")
		(25 "Edge.Cuts" user "Board Geometry/Outline")
		(27 "Margin" user)
		(31 "F.CrtYd" user "Package Geometry/Place Bound Top")
		(29 "B.CrtYd" user "Package Geometry/Place Bound Bottom")
		(35 "F.Fab" user "Ref Des/Assembly Top")
		(33 "B.Fab" user "Ref Des/Assembly Bottom")
	)
	(footprint ""
		(layer "F.Cu")
		(at 131.425696 -341.729822 -90)
		(property "Reference" "PC510"
			(at 0 0 270)
			(layer "F.SilkS")
			(hide yes)
			(effects
				(font
					(size 1.27 1.27)
				)
			)
		)
		(property "Value" ""
			(at 0 0 270)
			(layer "F.Fab")
			(effects
				(font
					(size 1.27 1.27)
				)
			)
		)
		(duplicate_pad_numbers_are_jumpers no)
		(fp_line
			(start -0.7874 0.4064)
			(end -0.7874 -0.4064)
			(stroke
				(width 0.1524)
				(type default)
			)
			(layer "F.SilkS")
		)
		(fp_line
			(start 0.7874 0.4064)
			(end -0.7874 0.4064)
			(stroke
				(width 0.1524)
				(type default)
			)
			(layer "F.SilkS")
		)
		(fp_line
			(start -0.7874 -0.4064)
			(end 0.7874 -0.4064)
			(stroke
				(width 0.1524)
				(type default)
			)
			(layer "F.SilkS")
		)
		(fp_line
			(start 0.7874 -0.4064)
			(end 0.7874 0.4064)
			(stroke
				(width 0.1524)
				(type default)
			)
			(layer "F.SilkS")
		)
		(fp_line
			(start -0.67945 0.3048)
			(end -0.67945 -0.305054)
			(stroke
				(width 0.1)
				(type default)
			)
			(layer "F.Fab")
		)
		(fp_line
			(start -0.12065 0.3048)
			(end -0.67945 0.3048)
			(stroke
				(width 0.1)
				(type default)
			)
			(layer "F.Fab")
		)
		(fp_line
			(start 0.120396 0.3048)
			(end 0.120396 0.2794)
			(stroke
				(width 0.1)
				(type default)
			)
			(layer "F.Fab")
		)
		(fp_line
			(start 0.67945 0.3048)
			(end 0.120396 0.3048)
			(stroke
				(width 0.1)
				(type default)
			)
			(layer "F.Fab")
		)
		(fp_line
			(start -0.12065 0.2794)
			(end -0.12065 0.3048)
			(stroke
				(width 0.1)
				(type default)
			)
			(layer "F.Fab")
		)
		(fp_line
			(start 0.120396 0.2794)
			(end -0.12065 0.2794)
			(stroke
				(width 0.1)
				(type default)
			)
			(layer "F.Fab")
		)
		(fp_line
			(start -0.12065 -0.2794)
			(end 0.12065 -0.2794)
			(stroke
				(width 0.1)
				(type default)
			)
			(layer "F.Fab")
		)
		(fp_line
			(start 0.12065 -0.2794)
			(end 0.12065 -0.3048)
			(stroke
				(width 0.1)
				(type default)
			)
			(layer "F.Fab")
		)
		(fp_line
			(start 0.12065 -0.3048)
			(end 0.67945 -0.3048)
			(stroke
				(width 0.1)
				(type default)
			)
			(layer "F.Fab")
		)
		(fp_line
			(start 0.67945 -0.3048)
			(end 0.67945 0.3048)
			(stroke
				(width 0.1)
				(type default)
			)
			(layer "F.Fab")
		)
		(fp_line
			(start -0.67945 -0.305054)
			(end -0.12065 -0.305054)
			(stroke
				(width 0.1)
				(type default)
			)
			(layer "F.Fab")
		)
		(fp_line
			(start -0.12065 -0.305054)
			(end -0.12065 -0.2794)
			(stroke
				(width 0.1)
				(type default)
			)
			(layer "F.Fab")
		)
		(pad "1" smd circle
			(at -0.40005 0 270)
			(size 0 0)
			(layers "F.Cu" "F.Mask" "F.Paste")
			(net "SW_PVCCIN_CPU1_BOOT5_R")
		)
		(pad "2" smd circle
			(at 0.40005 0 270)
			(size 0 0)
			(layers "F.Cu" "F.Mask" "F.Paste")
			(net "SW_PVCCIN_CPU1_BOOTR5")
		)
	)
	(footprint ""
		(layer "F.Cu")
		(at 168.11371 -129.553716 90)
		(property "Reference" "R1640"
			(at 0 0 90)
			(layer "F.SilkS")
			(hide yes)
			(effects
				(font
					(size 1.27 1.27)
				)
			)
		)
		(property "Value" ""
			(at 0 0 90)
			(layer "F.Fab")
			(effects
				(font
					(size 1.27 1.27)
				)
			)
		)
		(duplicate_pad_numbers_are_jumpers no)
		(fp_line
			(start 0.7874 -0.4064)
			(end 0.7874 0.4064)
			(stroke
				(width 0.1524)
				(type default)
			)
			(layer "F.SilkS")
		)
		(fp_line
			(start -0.7874 -0.4064)
			(end 0.7874 -0.4064)
			(stroke
				(width 0.1524)
				(type default)
			)
			(layer "F.SilkS")
		)
		(fp_line
			(start 0.7874 0.4064)
			(end -0.7874 0.4064)
			(stroke
				(width 0.1524)
				(type default)
			)
			(layer "F.SilkS")
		)
		(fp_line
			(start -0.7874 0.4064)
			(end -0.7874 -0.4064)
			(stroke
				(width 0.1524)
				(type default)
			)
			(layer "F.SilkS")
		)
		(fp_line
			(start -0.12065 -0.305054)
			(end -0.12065 -0.2794)
			(stroke
				(width 0.1)
				(type default)
			)
			(layer "F.Fab")
		)
		(fp_line
			(start -0.67945 -0.305054)
			(end -0.12065 -0.305054)
			(stroke
				(width 0.1)
				(type default)
			)
			(layer "F.Fab")
		)
		(fp_line
			(start 0.67945 -0.3048)
			(end 0.67945 0.3048)
			(stroke
				(width 0.1)
				(type default)
			)
			(layer "F.Fab")
		)
		(fp_line
			(start 0.12065 -0.3048)
			(end 0.67945 -0.3048)
			(stroke
				(width 0.1)
				(type default)
			)
			(layer "F.Fab")
		)
		(fp_line
			(start 0.12065 -0.2794)
			(end 0.12065 -0.3048)
			(stroke
				(width 0.1)
				(type default)
			)
			(layer "F.Fab")
		)
		(fp_line
			(start -0.12065 -0.2794)
			(end 0.12065 -0.2794)
			(stroke
				(width 0.1)
				(type default)
			)
			(layer "F.Fab")
		)
		(fp_line
			(start 0.120396 0.2794)
			(end -0.12065 0.2794)
			(stroke
				(width 0.1)
				(type default)
			)
			(layer "F.Fab")
		)
		(fp_line
			(start -0.12065 0.2794)
			(end -0.12065 0.3048)
			(stroke
				(width 0.1)
				(type default)
			)
			(layer "F.Fab")
		)
		(fp_line
			(start 0.67945 0.3048)
			(end 0.120396 0.3048)
			(stroke
				(width 0.1)
				(type default)
			)
			(layer "F.Fab")
		)
		(fp_line
			(start 0.120396 0.3048)
			(end 0.120396 0.2794)
			(stroke
				(width 0.1)
				(type default)
			)
			(layer "F.Fab")
		)
		(fp_line
			(start -0.12065 0.3048)
			(end -0.67945 0.3048)
			(stroke
				(width 0.1)
				(type default)
			)
			(layer "F.Fab")
		)
		(fp_line
			(start -0.67945 0.3048)
			(end -0.67945 -0.305054)
			(stroke
				(width 0.1)
				(type default)
			)
			(layer "F.Fab")
		)
		(pad "1" smd circle
			(at -0.40005 0 90)
			(size 0 0)
			(layers "F.Cu" "F.Mask" "F.Paste")
			(net "FM_P5V_EN")
		)
		(pad "2" smd circle
			(at 0.40005 0 90)
			(size 0 0)
			(layers "F.Cu" "F.Mask" "F.Paste")
			(net "VR_P5V_EN")
		)
	)
)
